(kicad_sch
	(version 20250114)
	(generator "eeschema")
	(generator_version "9.0")
	(paper "A3")
	(title_block
		(title "LPDDR4 Test Board")
		(date "2024-02-12")
		(rev "1.1.5")
	)
	(text "HyperRAM"
		(exclude_from_sim no)
		(at 200.025 111.125 0)
		(effects
			(font
				(size 2.9972 2.9972)
				(thickness 0.5994)
				(bold yes)
			)
			(justify left bottom)
		)
	)
	(junction
		(at 228.6 121.285)
		(diameter 0)
		(color 0 0 0 0)
	)
	(junction
		(at 181.61 121.285)
		(diameter 0)
		(color 0 0 0 0)
	)
	(junction
		(at 187.96 123.825)
		(diameter 0)
		(color 0 0 0 0)
	)
	(junction
		(at 240.03 121.285)
		(diameter 0)
		(color 0 0 0 0)
	)
	(junction
		(at 247.65 121.285)
		(diameter 0)
		(color 0 0 0 0)
	)
	(junction
		(at 228.6 159.385)
		(diameter 0)
		(color 0 0 0 0)
	)
	(junction
		(at 232.41 121.285)
		(diameter 0)
		(color 0 0 0 0)
	)
	(wire
		(pts
			(xy 195.58 131.445) (xy 173.99 131.445)
		)
		(stroke
			(width 0)
			(type default)
		)
	)
	(wire
		(pts
			(xy 187.96 123.825) (xy 187.96 118.745)
		)
		(stroke
			(width 0)
			(type default)
		)
	)
	(wire
		(pts
			(xy 226.06 121.285) (xy 228.6 121.285)
		)
		(stroke
			(width 0)
			(type default)
		)
	)
	(wire
		(pts
			(xy 195.58 121.285) (xy 181.61 121.285)
		)
		(stroke
			(width 0)
			(type default)
		)
	)
	(wire
		(pts
			(xy 232.41 121.285) (xy 232.41 118.745)
		)
		(stroke
			(width 0)
			(type default)
		)
	)
	(wire
		(pts
			(xy 240.03 123.825) (xy 240.03 121.285)
		)
		(stroke
			(width 0)
			(type default)
		)
	)
	(wire
		(pts
			(xy 181.61 113.665) (xy 181.61 111.125)
		)
		(stroke
			(width 0)
			(type default)
		)
	)
	(wire
		(pts
			(xy 226.06 156.845) (xy 228.6 156.845)
		)
		(stroke
			(width 0)
			(type default)
		)
	)
	(wire
		(pts
			(xy 226.06 159.385) (xy 228.6 159.385)
		)
		(stroke
			(width 0)
			(type default)
		)
	)
	(wire
		(pts
			(xy 247.65 121.285) (xy 255.27 121.285)
		)
		(stroke
			(width 0)
			(type default)
		)
	)
	(wire
		(pts
			(xy 240.03 121.285) (xy 247.65 121.285)
		)
		(stroke
			(width 0)
			(type default)
		)
	)
	(wire
		(pts
			(xy 177.8 159.385) (xy 195.58 159.385)
		)
		(stroke
			(width 0)
			(type default)
		)
	)
	(wire
		(pts
			(xy 255.27 121.285) (xy 255.27 123.825)
		)
		(stroke
			(width 0)
			(type default)
		)
	)
	(wire
		(pts
			(xy 195.58 154.305) (xy 177.8 154.305)
		)
		(stroke
			(width 0)
			(type default)
		)
	)
	(wire
		(pts
			(xy 187.96 113.665) (xy 187.96 111.125)
		)
		(stroke
			(width 0)
			(type default)
		)
	)
	(wire
		(pts
			(xy 226.06 123.825) (xy 228.6 123.825)
		)
		(stroke
			(width 0)
			(type default)
		)
	)
	(wire
		(pts
			(xy 232.41 128.905) (xy 232.41 131.445)
		)
		(stroke
			(width 0)
			(type default)
		)
	)
	(wire
		(pts
			(xy 247.65 121.285) (xy 247.65 123.825)
		)
		(stroke
			(width 0)
			(type default)
		)
	)
	(wire
		(pts
			(xy 177.8 136.525) (xy 195.58 136.525)
		)
		(stroke
			(width 0)
			(type default)
		)
	)
	(wire
		(pts
			(xy 228.6 159.385) (xy 228.6 161.925)
		)
		(stroke
			(width 0)
			(type default)
		)
	)
	(wire
		(pts
			(xy 232.41 121.285) (xy 240.03 121.285)
		)
		(stroke
			(width 0)
			(type default)
		)
	)
	(wire
		(pts
			(xy 181.61 121.285) (xy 181.61 118.745)
		)
		(stroke
			(width 0)
			(type default)
		)
	)
	(wire
		(pts
			(xy 255.27 128.905) (xy 255.27 131.445)
		)
		(stroke
			(width 0)
			(type default)
		)
	)
	(wire
		(pts
			(xy 228.6 121.285) (xy 228.6 123.825)
		)
		(stroke
			(width 0)
			(type default)
		)
	)
	(wire
		(pts
			(xy 228.6 121.285) (xy 232.41 121.285)
		)
		(stroke
			(width 0)
			(type default)
		)
	)
	(wire
		(pts
			(xy 232.41 123.825) (xy 232.41 121.285)
		)
		(stroke
			(width 0)
			(type default)
		)
	)
	(wire
		(pts
			(xy 177.8 146.685) (xy 195.58 146.685)
		)
		(stroke
			(width 0)
			(type default)
		)
	)
	(wire
		(pts
			(xy 240.03 128.905) (xy 240.03 131.445)
		)
		(stroke
			(width 0)
			(type default)
		)
	)
	(wire
		(pts
			(xy 247.65 128.905) (xy 247.65 131.445)
		)
		(stroke
			(width 0)
			(type default)
		)
	)
	(wire
		(pts
			(xy 228.6 156.845) (xy 228.6 159.385)
		)
		(stroke
			(width 0)
			(type default)
		)
	)
	(wire
		(pts
			(xy 187.96 123.825) (xy 173.99 123.825)
		)
		(stroke
			(width 0)
			(type default)
		)
	)
	(wire
		(pts
			(xy 177.8 141.605) (xy 195.58 141.605)
		)
		(stroke
			(width 0)
			(type default)
		)
	)
	(wire
		(pts
			(xy 195.58 149.225) (xy 177.8 149.225)
		)
		(stroke
			(width 0)
			(type default)
		)
	)
	(wire
		(pts
			(xy 195.58 128.905) (xy 173.99 128.905)
		)
		(stroke
			(width 0)
			(type default)
		)
	)
	(wire
		(pts
			(xy 177.8 151.765) (xy 195.58 151.765)
		)
		(stroke
			(width 0)
			(type default)
		)
	)
	(wire
		(pts
			(xy 195.58 144.145) (xy 177.8 144.145)
		)
		(stroke
			(width 0)
			(type default)
		)
	)
	(wire
		(pts
			(xy 195.58 123.825) (xy 187.96 123.825)
		)
		(stroke
			(width 0)
			(type default)
		)
	)
	(wire
		(pts
			(xy 195.58 139.065) (xy 177.8 139.065)
		)
		(stroke
			(width 0)
			(type default)
		)
	)
	(wire
		(pts
			(xy 181.61 121.285) (xy 173.99 121.285)
		)
		(stroke
			(width 0)
			(type default)
		)
	)
	(global_label "HR_CKP"
		(shape input)
		(at 173.99 128.905 180)
		(fields_autoplaced yes)
		(effects
			(font
				(size 1.27 1.27)
			)
			(justify right)
		)
		(property "Intersheetrefs" "${INTERSHEET_REFS}"
			(at 164.2877 128.8256 0)
			(effects
				(font
					(size 1.27 1.27)
				)
				(justify right)
				(hide yes)
			)
		)
	)
	(global_label "HR_DQ1"
		(shape input)
		(at 177.8 139.065 180)
		(fields_autoplaced yes)
		(effects
			(font
				(size 1.27 1.27)
			)
			(justify right)
		)
		(property "Intersheetrefs" "${INTERSHEET_REFS}"
			(at 168.0977 138.9856 0)
			(effects
				(font
					(size 1.27 1.27)
				)
				(justify right)
				(hide yes)
			)
		)
	)
	(global_label "3V3_SYS"
		(shape input)
		(at 232.41 118.745 90)
		(fields_autoplaced yes)
		(effects
			(font
				(size 1.27 1.27)
			)
			(justify left)
		)
		(property "Intersheetrefs" "${INTERSHEET_REFS}"
			(at 232.3306 108.4379 90)
			(effects
				(font
					(size 1.27 1.27)
				)
				(justify left)
				(hide yes)
			)
		)
	)
	(global_label "HR_DQ4"
		(shape input)
		(at 177.8 146.685 180)
		(fields_autoplaced yes)
		(effects
			(font
				(size 1.27 1.27)
			)
			(justify right)
		)
		(property "Intersheetrefs" "${INTERSHEET_REFS}"
			(at 168.0977 146.6056 0)
			(effects
				(font
					(size 1.27 1.27)
				)
				(justify right)
				(hide yes)
			)
		)
	)
	(global_label "HR_DQ7"
		(shape input)
		(at 177.8 154.305 180)
		(fields_autoplaced yes)
		(effects
			(font
				(size 1.27 1.27)
			)
			(justify right)
		)
		(property "Intersheetrefs" "${INTERSHEET_REFS}"
			(at 168.0977 154.2256 0)
			(effects
				(font
					(size 1.27 1.27)
				)
				(justify right)
				(hide yes)
			)
		)
	)
	(global_label "HR_DQ0"
		(shape input)
		(at 177.8 136.525 180)
		(fields_autoplaced yes)
		(effects
			(font
				(size 1.27 1.27)
			)
			(justify right)
		)
		(property "Intersheetrefs" "${INTERSHEET_REFS}"
			(at 168.0977 136.4456 0)
			(effects
				(font
					(size 1.27 1.27)
				)
				(justify right)
				(hide yes)
			)
		)
	)
	(global_label "HR_CS"
		(shape input)
		(at 173.99 123.825 180)
		(fields_autoplaced yes)
		(effects
			(font
				(size 1.27 1.27)
			)
			(justify right)
		)
		(property "Intersheetrefs" "${INTERSHEET_REFS}"
			(at 165.6182 123.7456 0)
			(effects
				(font
					(size 1.27 1.27)
				)
				(justify right)
				(hide yes)
			)
		)
	)
	(global_label "HR_DQ3"
		(shape input)
		(at 177.8 144.145 180)
		(fields_autoplaced yes)
		(effects
			(font
				(size 1.27 1.27)
			)
			(justify right)
		)
		(property "Intersheetrefs" "${INTERSHEET_REFS}"
			(at 168.0977 144.0656 0)
			(effects
				(font
					(size 1.27 1.27)
				)
				(justify right)
				(hide yes)
			)
		)
	)
	(global_label "HR_RST"
		(shape input)
		(at 173.99 121.285 180)
		(fields_autoplaced yes)
		(effects
			(font
				(size 1.27 1.27)
			)
			(justify right)
		)
		(property "Intersheetrefs" "${INTERSHEET_REFS}"
			(at 164.6506 121.2056 0)
			(effects
				(font
					(size 1.27 1.27)
				)
				(justify right)
				(hide yes)
			)
		)
	)
	(global_label "3V3_SYS"
		(shape input)
		(at 187.96 111.125 90)
		(fields_autoplaced yes)
		(effects
			(font
				(size 1.27 1.27)
			)
			(justify left)
		)
		(property "Intersheetrefs" "${INTERSHEET_REFS}"
			(at 187.8806 100.8179 90)
			(effects
				(font
					(size 1.27 1.27)
				)
				(justify left)
				(hide yes)
			)
		)
	)
	(global_label "HR_DQ6"
		(shape input)
		(at 177.8 151.765 180)
		(fields_autoplaced yes)
		(effects
			(font
				(size 1.27 1.27)
			)
			(justify right)
		)
		(property "Intersheetrefs" "${INTERSHEET_REFS}"
			(at 168.0977 151.6856 0)
			(effects
				(font
					(size 1.27 1.27)
				)
				(justify right)
				(hide yes)
			)
		)
	)
	(global_label "HR_RW"
		(shape input)
		(at 177.8 159.385 180)
		(fields_autoplaced yes)
		(effects
			(font
				(size 1.27 1.27)
			)
			(justify right)
		)
		(property "Intersheetrefs" "${INTERSHEET_REFS}"
			(at 169.1863 159.3056 0)
			(effects
				(font
					(size 1.27 1.27)
				)
				(justify right)
				(hide yes)
			)
		)
	)
	(global_label "3V3_SYS"
		(shape input)
		(at 181.61 111.125 90)
		(fields_autoplaced yes)
		(effects
			(font
				(size 1.27 1.27)
			)
			(justify left)
		)
		(property "Intersheetrefs" "${INTERSHEET_REFS}"
			(at 181.5306 100.8179 90)
			(effects
				(font
					(size 1.27 1.27)
				)
				(justify left)
				(hide yes)
			)
		)
	)
	(global_label "HR_DQ5"
		(shape input)
		(at 177.8 149.225 180)
		(fields_autoplaced yes)
		(effects
			(font
				(size 1.27 1.27)
			)
			(justify right)
		)
		(property "Intersheetrefs" "${INTERSHEET_REFS}"
			(at 168.0977 149.1456 0)
			(effects
				(font
					(size 1.27 1.27)
				)
				(justify right)
				(hide yes)
			)
		)
	)
	(global_label "HR_CKN"
		(shape input)
		(at 173.99 131.445 180)
		(fields_autoplaced yes)
		(effects
			(font
				(size 1.27 1.27)
			)
			(justify right)
		)
		(property "Intersheetrefs" "${INTERSHEET_REFS}"
			(at 164.2272 131.3656 0)
			(effects
				(font
					(size 1.27 1.27)
				)
				(justify right)
				(hide yes)
			)
		)
	)
	(global_label "HR_DQ2"
		(shape input)
		(at 177.8 141.605 180)
		(fields_autoplaced yes)
		(effects
			(font
				(size 1.27 1.27)
			)
			(justify right)
		)
		(property "Intersheetrefs" "${INTERSHEET_REFS}"
			(at 168.0977 141.5256 0)
			(effects
				(font
					(size 1.27 1.27)
				)
				(justify right)
				(hide yes)
			)
		)
	)
	(symbol
		(lib_id "antmicroMemory:S27KL0641DABHI023")
		(at 195.58 121.285 0)
		(unit 1)
		(exclude_from_sim no)
		(in_bom yes)
		(on_board yes)
		(dnp no)
		(property "Reference" "U1"
			(at 198.12 115.57 0)
			(effects
				(font
					(size 1.27 1.27)
					(thickness 0.15)
				)
				(justify left bottom)
			)
		)
		(property "Value" "S27KL0641DABHI023"
			(at 198.12 118.11 0)
			(effects
				(font
					(size 1.27 1.27)
					(thickness 0.15)
				)
				(justify left bottom)
			)
		)
		(property "Footprint" "antmicro-footprints:FBGA-25-24_6x8mm_Layout5x5_P1mm"
			(at 241.3 131.445 0)
			(effects
				(font
					(size 1.27 1.27)
					(thickness 0.15)
				)
				(justify left bottom)
				(hide yes)
			)
		)
		(property "Datasheet" "https://www.mouser.pl/datasheet/2/196/CYPR_S_A0011122227_1-3004854.pdf"
			(at 241.3 133.985 0)
			(effects
				(font
					(size 1.27 1.27)
					(thickness 0.15)
				)
				(justify left bottom)
				(hide yes)
			)
		)
		(property "Description" ""
			(at 195.58 121.285 0)
			(effects
				(font
					(size 1.27 1.27)
				)
			)
		)
		(property "Manufacturer" "Cypress Semiconductor"
			(at 241.3 136.525 0)
			(effects
				(font
					(size 1.27 1.27)
					(thickness 0.15)
				)
				(justify left bottom)
				(hide yes)
			)
		)
		(property "MPN" "S27KL0641DABHI023"
			(at 241.3 139.065 0)
			(effects
				(font
					(size 1.27 1.27)
					(thickness 0.15)
				)
				(justify left bottom)
				(hide yes)
			)
		)
		(property "Author" "Antmicro"
			(at 241.3 141.605 0)
			(effects
				(font
					(size 1.27 1.27)
					(thickness 0.15)
				)
				(justify left bottom)
				(hide yes)
			)
		)
		(property "License" "Apache-2.0"
			(at 241.3 144.145 0)
			(effects
				(font
					(size 1.27 1.27)
					(thickness 0.15)
				)
				(justify left bottom)
				(hide yes)
			)
		)
		(pin "A2"
		)
		(pin "A3"
		)
		(pin "A4"
		)
		(pin "A5"
		)
		(pin "B1"
		)
		(pin "B2"
		)
		(pin "B3"
		)
		(pin "B4"
		)
		(pin "B5"
		)
		(pin "C1"
		)
		(pin "C2"
		)
		(pin "C3"
		)
		(pin "C4"
		)
		(pin "C5"
		)
		(pin "D1"
		)
		(pin "D2"
		)
		(pin "D3"
		)
		(pin "D4"
		)
		(pin "D5"
		)
		(pin "E1"
		)
		(pin "E2"
		)
		(pin "E3"
		)
		(pin "E4"
		)
		(pin "E5"
		)
		(instances
			(project "lpddr4-test-board"
				(path ""
					(reference "U1")
					(unit 1)
				)
			)
		)
	)
	(symbol
		(lib_id "antmicroCapacitors0603:C_47u_0603")
		(at 232.41 123.825 270)
		(unit 1)
		(exclude_from_sim no)
		(in_bom yes)
		(on_board yes)
		(dnp no)
		(property "Reference" "C1"
			(at 233.045 125.73 90)
			(effects
				(font
					(size 1.27 1.27)
					(thickness 0.15)
				)
				(justify left bottom)
			)
		)
		(property "Value" "C_47u_0603"
			(at 222.25 144.145 0)
			(effects
				(font
					(size 1.27 1.27)
					(thickness 0.15)
				)
				(justify left bottom)
				(hide yes)
			)
		)
		(property "Footprint" "antmicro-footprints:C_0603_1608Metric"
			(at 219.71 144.145 0)
			(effects
				(font
					(size 1.27 1.27)
					(thickness 0.15)
				)
				(justify left bottom)
				(hide yes)
			)
		)
		(property "Datasheet" " "
			(at 217.17 144.145 0)
			(effects
				(font
					(size 1.27 1.27)
					(thickness 0.15)
				)
				(justify left bottom)
				(hide yes)
			)
		)
		(property "Description" ""
			(at 232.41 123.825 0)
			(effects
				(font
					(size 1.27 1.27)
				)
			)
		)
		(property "Manufacturer" "Murata"
			(at 212.09 144.145 0)
			(effects
				(font
					(size 1.27 1.27)
					(thickness 0.15)
				)
				(justify left bottom)
				(hide yes)
			)
		)
		(property "MPN" "GRM188R60J476ME15D"
			(at 214.63 144.145 0)
			(effects
				(font
					(size 1.27 1.27)
					(thickness 0.15)
				)
				(justify left bottom)
				(hide yes)
			)
		)
		(property "Val" "47u"
			(at 233.045 129.54 90)
			(effects
				(font
					(size 1.27 1.27)
					(thickness 0.15)
				)
				(justify left bottom)
			)
		)
		(property "License" "Apache-2.0"
			(at 209.55 144.145 0)
			(effects
				(font
					(size 1.27 1.27)
					(thickness 0.15)
				)
				(justify left bottom)
				(hide yes)
			)
		)
		(property "Author" "Antmicro"
			(at 207.01 144.145 0)
			(effects
				(font
					(size 1.27 1.27)
					(thickness 0.15)
				)
				(justify left bottom)
				(hide yes)
			)
		)
		(property "Voltage" ""
			(at 204.47 144.145 0)
			(effects
				(font
					(size 1.27 1.27)
				)
				(justify left bottom)
				(hide yes)
			)
		)
		(property "Dielectric" ""
			(at 201.93 144.145 0)
			(effects
				(font
					(size 1.27 1.27)
				)
				(justify left bottom)
				(hide yes)
			)
		)
		(pin "1"
		)
		(pin "2"
		)
		(instances
			(project "lpddr4-test-board"
				(path ""
					(reference "C1")
					(unit 1)
				)
			)
		)
	)
	(symbol
		(lib_id "antmicroCapacitorsmisc:C_100n_6V3_0402")
		(at 247.65 123.825 270)
		(unit 1)
		(exclude_from_sim no)
		(in_bom yes)
		(on_board yes)
		(dnp no)
		(property "Reference" "C3"
			(at 248.285 125.73 90)
			(effects
				(font
					(size 1.27 1.27)
					(thickness 0.15)
				)
				(justify left bottom)
			)
		)
		(property "Value" "C_100n_6V3_0402"
			(at 237.49 144.145 0)
			(effects
				(font
					(size 1.27 1.27)
					(thickness 0.15)
				)
				(justify left bottom)
				(hide yes)
			)
		)
		(property "Footprint" "antmicro-footprints:C_0402_1005Metric"
			(at 234.95 144.145 0)
			(effects
				(font
					(size 1.27 1.27)
					(thickness 0.15)
				)
				(justify left bottom)
				(hide yes)
			)
		)
		(property "Datasheet" " "
			(at 232.41 144.145 0)
			(effects
				(font
					(size 1.27 1.27)
					(thickness 0.15)
				)
				(justify left bottom)
				(hide yes)
			)
		)
		(property "Description" ""
			(at 247.65 123.825 0)
			(effects
				(font
					(size 1.27 1.27)
				)
			)
		)
		(property "Manufacturer" "Walsin"
			(at 227.33 144.145 0)
			(effects
				(font
					(size 1.27 1.27)
					(thickness 0.15)
				)
				(justify left bottom)
				(hide yes)
			)
		)
		(property "MPN" "0402X104K6R3CT"
			(at 229.87 144.145 0)
			(effects
				(font
					(size 1.27 1.27)
					(thickness 0.15)
				)
				(justify left bottom)
				(hide yes)
			)
		)
		(property "Val" "100n"
			(at 248.285 129.54 90)
			(effects
				(font
					(size 1.27 1.27)
					(thickness 0.15)
				)
				(justify left bottom)
			)
		)
		(property "License" "Apache-2.0"
			(at 224.79 144.145 0)
			(effects
				(font
					(size 1.27 1.27)
					(thickness 0.15)
				)
				(justify left bottom)
				(hide yes)
			)
		)
		(property "Author" "Antmicro"
			(at 222.25 144.145 0)
			(effects
				(font
					(size 1.27 1.27)
					(thickness 0.15)
				)
				(justify left bottom)
				(hide yes)
			)
		)
		(property "Voltage" ""
			(at 219.71 144.145 0)
			(effects
				(font
					(size 1.27 1.27)
				)
				(justify left bottom)
				(hide yes)
			)
		)
		(property "Dielectric" ""
			(at 217.17 144.145 0)
			(effects
				(font
					(size 1.27 1.27)
				)
				(justify left bottom)
				(hide yes)
			)
		)
		(pin "1"
		)
		(pin "2"
		)
		(instances
			(project "lpddr4-test-board"
				(path ""
					(reference "C3")
					(unit 1)
				)
			)
		)
	)
	(symbol
		(lib_id "antmicropower:GND")
		(at 232.41 131.445 0)
		(unit 1)
		(exclude_from_sim no)
		(in_bom yes)
		(on_board yes)
		(dnp no)
		(property "Reference" "#PWR02"
			(at 241.3 133.985 0)
			(effects
				(font
					(size 1.27 1.27)
					(thickness 0.15)
				)
				(justify left bottom)
				(hide yes)
			)
		)
		(property "Value" "GND"
			(at 230.505 135.89 0)
			(effects
				(font
					(size 1.27 1.27)
					(thickness 0.15)
				)
				(justify left bottom)
			)
		)
		(property "Footprint" ""
			(at 241.3 139.065 0)
			(effects
				(font
					(size 1.27 1.27)
					(thickness 0.15)
				)
				(justify left bottom)
				(hide yes)
			)
		)
		(property "Datasheet" ""
			(at 241.3 144.145 0)
			(effects
				(font
					(size 1.27 1.27)
					(thickness 0.15)
				)
				(justify left bottom)
				(hide yes)
			)
		)
		(property "Description" ""
			(at 232.41 131.445 0)
			(effects
				(font
					(size 1.27 1.27)
				)
			)
		)
		(property "Author" "Antmicro"
			(at 241.3 139.065 0)
			(effects
				(font
					(size 1.27 1.27)
					(thickness 0.15)
				)
				(justify left bottom)
				(hide yes)
			)
		)
		(property "License" "Apache-2.0"
			(at 241.3 141.605 0)
			(effects
				(font
					(size 1.27 1.27)
					(thickness 0.15)
				)
				(justify left bottom)
				(hide yes)
			)
		)
		(pin "1"
		)
		(instances
			(project "lpddr4-test-board"
				(path ""
					(reference "#PWR02")
					(unit 1)
				)
			)
		)
	)
	(symbol
		(lib_id "antmicroResistors0402:R_10k_0402")
		(at 181.61 113.665 270)
		(unit 1)
		(exclude_from_sim no)
		(in_bom yes)
		(on_board yes)
		(dnp no)
		(property "Reference" "R1"
			(at 182.88 116.205 90)
			(effects
				(font
					(size 1.27 1.27)
					(thickness 0.15)
				)
				(justify left bottom)
			)
		)
		(property "Value" "R_10k_0402"
			(at 168.91 133.985 0)
			(effects
				(font
					(size 1.27 1.27)
					(thickness 0.15)
				)
				(justify left bottom)
				(hide yes)
			)
		)
		(property "Footprint" "antmicro-footprints:R_0402_1005Metric"
			(at 166.37 133.985 0)
			(effects
				(font
					(size 1.27 1.27)
					(thickness 0.15)
				)
				(justify left bottom)
				(hide yes)
			)
		)
		(property "Datasheet" "https://www.bourns.com/docs/product-datasheets/cr.pdf"
			(at 163.83 133.985 0)
			(effects
				(font
					(size 1.27 1.27)
					(thickness 0.15)
				)
				(justify left bottom)
				(hide yes)
			)
		)
		(property "Description" ""
			(at 181.61 113.665 0)
			(effects
				(font
					(size 1.27 1.27)
				)
			)
		)
		(property "Manufacturer" "Bourns"
			(at 158.75 133.985 0)
			(effects
				(font
					(size 1.27 1.27)
					(thickness 0.15)
				)
				(justify left bottom)
				(hide yes)
			)
		)
		(property "MPN" "CR0402-FX-1002GLF"
			(at 161.29 133.985 0)
			(effects
				(font
					(size 1.27 1.27)
					(thickness 0.15)
				)
				(justify left bottom)
				(hide yes)
			)
		)
		(property "Val" "10k"
			(at 182.88 118.745 90)
			(effects
				(font
					(size 1.27 1.27)
					(thickness 0.15)
				)
				(justify left bottom)
			)
		)
		(property "License" "Apache-2.0"
			(at 156.21 133.985 0)
			(effects
				(font
					(size 1.27 1.27)
					(thickness 0.15)
				)
				(justify left bottom)
				(hide yes)
			)
		)
		(property "Author" "Antmicro"
			(at 153.67 133.985 0)
			(effects
				(font
					(size 1.27 1.27)
					(thickness 0.15)
				)
				(justify left bottom)
				(hide yes)
			)
		)
		(property "Tolerance" "1%"
			(at 171.45 133.985 0)
			(effects
				(font
					(size 1.27 1.27)
				)
				(justify left bottom)
				(hide yes)
			)
		)
		(pin "1"
		)
		(pin "2"
		)
		(instances
			(project "lpddr4-test-board"
				(path ""
					(reference "R1")
					(unit 1)
				)
			)
		)
	)
	(symbol
		(lib_id "antmicropower:GND")
		(at 240.03 131.445 0)
		(unit 1)
		(exclude_from_sim no)
		(in_bom yes)
		(on_board yes)
		(dnp no)
		(property "Reference" "#PWR03"
			(at 248.92 133.985 0)
			(effects
				(font
					(size 1.27 1.27)
					(thickness 0.15)
				)
				(justify left bottom)
				(hide yes)
			)
		)
		(property "Value" "GND"
			(at 238.125 135.89 0)
			(effects
				(font
					(size 1.27 1.27)
					(thickness 0.15)
				)
				(justify left bottom)
			)
		)
		(property "Footprint" ""
			(at 248.92 139.065 0)
			(effects
				(font
					(size 1.27 1.27)
					(thickness 0.15)
				)
				(justify left bottom)
				(hide yes)
			)
		)
		(property "Datasheet" ""
			(at 248.92 144.145 0)
			(effects
				(font
					(size 1.27 1.27)
					(thickness 0.15)
				)
				(justify left bottom)
				(hide yes)
			)
		)
		(property "Description" ""
			(at 240.03 131.445 0)
			(effects
				(font
					(size 1.27 1.27)
				)
			)
		)
		(property "Author" "Antmicro"
			(at 248.92 139.065 0)
			(effects
				(font
					(size 1.27 1.27)
					(thickness 0.15)
				)
				(justify left bottom)
				(hide yes)
			)
		)
		(property "License" "Apache-2.0"
			(at 248.92 141.605 0)
			(effects
				(font
					(size 1.27 1.27)
					(thickness 0.15)
				)
				(justify left bottom)
				(hide yes)
			)
		)
		(pin "1"
		)
		(instances
			(project "lpddr4-test-board"
				(path ""
					(reference "#PWR03")
					(unit 1)
				)
			)
		)
	)
	(symbol
		(lib_id "antmicropower:GND")
		(at 247.65 131.445 0)
		(unit 1)
		(exclude_from_sim no)
		(in_bom yes)
		(on_board yes)
		(dnp no)
		(property "Reference" "#PWR04"
			(at 256.54 133.985 0)
			(effects
				(font
					(size 1.27 1.27)
					(thickness 0.15)
				)
				(justify left bottom)
				(hide yes)
			)
		)
		(property "Value" "GND"
			(at 245.745 135.89 0)
			(effects
				(font
					(size 1.27 1.27)
					(thickness 0.15)
				)
				(justify left bottom)
			)
		)
		(property "Footprint" ""
			(at 256.54 139.065 0)
			(effects
				(font
					(size 1.27 1.27)
					(thickness 0.15)
				)
				(justify left bottom)
				(hide yes)
			)
		)
		(property "Datasheet" ""
			(at 256.54 144.145 0)
			(effects
				(font
					(size 1.27 1.27)
					(thickness 0.15)
				)
				(justify left bottom)
				(hide yes)
			)
		)
		(property "Description" ""
			(at 247.65 131.445 0)
			(effects
				(font
					(size 1.27 1.27)
				)
			)
		)
		(property "Author" "Antmicro"
			(at 256.54 139.065 0)
			(effects
				(font
					(size 1.27 1.27)
					(thickness 0.15)
				)
				(justify left bottom)
				(hide yes)
			)
		)
		(property "License" "Apache-2.0"
			(at 256.54 141.605 0)
			(effects
				(font
					(size 1.27 1.27)
					(thickness 0.15)
				)
				(justify left bottom)
				(hide yes)
			)
		)
		(pin "1"
		)
		(instances
			(project "lpddr4-test-board"
				(path ""
					(reference "#PWR04")
					(unit 1)
				)
			)
		)
	)
	(symbol
		(lib_id "antmicroCapacitorsmisc:C_100n_6V3_0402")
		(at 240.03 123.825 270)
		(unit 1)
		(exclude_from_sim no)
		(in_bom yes)
		(on_board yes)
		(dnp no)
		(property "Reference" "C2"
			(at 240.665 125.73 90)
			(effects
				(font
					(size 1.27 1.27)
					(thickness 0.15)
				)
				(justify left bottom)
			)
		)
		(property "Value" "C_100n_6V3_0402"
			(at 229.87 144.145 0)
			(effects
				(font
					(size 1.27 1.27)
					(thickness 0.15)
				)
				(justify left bottom)
				(hide yes)
			)
		)
		(property "Footprint" "antmicro-footprints:C_0402_1005Metric"
			(at 227.33 144.145 0)
			(effects
				(font
					(size 1.27 1.27)
					(thickness 0.15)
				)
				(justify left bottom)
				(hide yes)
			)
		)
		(property "Datasheet" " "
			(at 224.79 144.145 0)
			(effects
				(font
					(size 1.27 1.27)
					(thickness 0.15)
				)
				(justify left bottom)
				(hide yes)
			)
		)
		(property "Description" ""
			(at 240.03 123.825 0)
			(effects
				(font
					(size 1.27 1.27)
				)
			)
		)
		(property "Manufacturer" "Walsin"
			(at 219.71 144.145 0)
			(effects
				(font
					(size 1.27 1.27)
					(thickness 0.15)
				)
				(justify left bottom)
				(hide yes)
			)
		)
		(property "MPN" "0402X104K6R3CT"
			(at 222.25 144.145 0)
			(effects
				(font
					(size 1.27 1.27)
					(thickness 0.15)
				)
				(justify left bottom)
				(hide yes)
			)
		)
		(property "Val" "100n"
			(at 240.665 129.54 90)
			(effects
				(font
					(size 1.27 1.27)
					(thickness 0.15)
				)
				(justify left bottom)
			)
		)
		(property "License" "Apache-2.0"
			(at 217.17 144.145 0)
			(effects
				(font
					(size 1.27 1.27)
					(thickness 0.15)
				)
				(justify left bottom)
				(hide yes)
			)
		)
		(property "Author" "Antmicro"
			(at 214.63 144.145 0)
			(effects
				(font
					(size 1.27 1.27)
					(thickness 0.15)
				)
				(justify left bottom)
				(hide yes)
			)
		)
		(property "Voltage" ""
			(at 212.09 144.145 0)
			(effects
				(font
					(size 1.27 1.27)
				)
				(justify left bottom)
				(hide yes)
			)
		)
		(property "Dielectric" ""
			(at 209.55 144.145 0)
			(effects
				(font
					(size 1.27 1.27)
				)
				(justify left bottom)
				(hide yes)
			)
		)
		(pin "1"
		)
		(pin "2"
		)
		(instances
			(project "lpddr4-test-board"
				(path ""
					(reference "C2")
					(unit 1)
				)
			)
		)
	)
	(symbol
		(lib_id "antmicroResistors0402:R_10k_0402")
		(at 187.96 113.665 270)
		(unit 1)
		(exclude_from_sim no)
		(in_bom yes)
		(on_board yes)
		(dnp no)
		(property "Reference" "R2"
			(at 189.23 116.205 90)
			(effects
				(font
					(size 1.27 1.27)
					(thickness 0.15)
				)
				(justify left bottom)
			)
		)
		(property "Value" "R_10k_0402"
			(at 175.26 133.985 0)
			(effects
				(font
					(size 1.27 1.27)
					(thickness 0.15)
				)
				(justify left bottom)
				(hide yes)
			)
		)
		(property "Footprint" "antmicro-footprints:R_0402_1005Metric"
			(at 172.72 133.985 0)
			(effects
				(font
					(size 1.27 1.27)
					(thickness 0.15)
				)
				(justify left bottom)
				(hide yes)
			)
		)
		(property "Datasheet" "https://www.bourns.com/docs/product-datasheets/cr.pdf"
			(at 170.18 133.985 0)
			(effects
				(font
					(size 1.27 1.27)
					(thickness 0.15)
				)
				(justify left bottom)
				(hide yes)
			)
		)
		(property "Description" ""
			(at 187.96 113.665 0)
			(effects
				(font
					(size 1.27 1.27)
				)
			)
		)
		(property "Manufacturer" "Bourns"
			(at 165.1 133.985 0)
			(effects
				(font
					(size 1.27 1.27)
					(thickness 0.15)
				)
				(justify left bottom)
				(hide yes)
			)
		)
		(property "MPN" "CR0402-FX-1002GLF"
			(at 167.64 133.985 0)
			(effects
				(font
					(size 1.27 1.27)
					(thickness 0.15)
				)
				(justify left bottom)
				(hide yes)
			)
		)
		(property "Val" "10k"
			(at 189.23 118.745 90)
			(effects
				(font
					(size 1.27 1.27)
					(thickness 0.15)
				)
				(justify left bottom)
			)
		)
		(property "License" "Apache-2.0"
			(at 162.56 133.985 0)
			(effects
				(font
					(size 1.27 1.27)
					(thickness 0.15)
				)
				(justify left bottom)
				(hide yes)
			)
		)
		(property "Author" "Antmicro"
			(at 160.02 133.985 0)
			(effects
				(font
					(size 1.27 1.27)
					(thickness 0.15)
				)
				(justify left bottom)
				(hide yes)
			)
		)
		(property "Tolerance" "1%"
			(at 177.8 133.985 0)
			(effects
				(font
					(size 1.27 1.27)
				)
				(justify left bottom)
				(hide yes)
			)
		)
		(pin "1"
		)
		(pin "2"
		)
		(instances
			(project "lpddr4-test-board"
				(path ""
					(reference "R2")
					(unit 1)
				)
			)
		)
	)
	(symbol
		(lib_id "antmicropower:GND")
		(at 228.6 161.925 0)
		(mirror y)
		(unit 1)
		(exclude_from_sim no)
		(in_bom yes)
		(on_board yes)
		(dnp no)
		(property "Reference" "#PWR01"
			(at 219.71 164.465 0)
			(effects
				(font
					(size 1.27 1.27)
					(thickness 0.15)
				)
				(justify left bottom)
				(hide yes)
			)
		)
		(property "Value" "GND"
			(at 226.695 166.37 0)
			(effects
				(font
					(size 1.27 1.27)
					(thickness 0.15)
				)
				(justify right bottom)
			)
		)
		(property "Footprint" ""
			(at 219.71 169.545 0)
			(effects
				(font
					(size 1.27 1.27)
					(thickness 0.15)
				)
				(justify left bottom)
				(hide yes)
			)
		)
		(property "Datasheet" ""
			(at 219.71 174.625 0)
			(effects
				(font
					(size 1.27 1.27)
					(thickness 0.15)
				)
				(justify left bottom)
				(hide yes)
			)
		)
		(property "Description" ""
			(at 228.6 161.925 0)
			(effects
				(font
					(size 1.27 1.27)
				)
			)
		)
		(property "Author" "Antmicro"
			(at 219.71 169.545 0)
			(effects
				(font
					(size 1.27 1.27)
					(thickness 0.15)
				)
				(justify left bottom)
				(hide yes)
			)
		)
		(property "License" "Apache-2.0"
			(at 219.71 172.085 0)
			(effects
				(font
					(size 1.27 1.27)
					(thickness 0.15)
				)
				(justify left bottom)
				(hide yes)
			)
		)
		(pin "1"
		)
		(instances
			(project "lpddr4-test-board"
				(path ""
					(reference "#PWR01")
					(unit 1)
				)
			)
		)
	)
	(symbol
		(lib_id "antmicroCapacitorsmisc:C_100n_6V3_0402")
		(at 255.27 123.825 270)
		(unit 1)
		(exclude_from_sim no)
		(in_bom yes)
		(on_board yes)
		(dnp no)
		(property "Reference" "C4"
			(at 255.905 125.73 90)
			(effects
				(font
					(size 1.27 1.27)
					(thickness 0.15)
				)
				(justify left bottom)
			)
		)
		(property "Value" "C_100n_6V3_0402"
			(at 245.11 144.145 0)
			(effects
				(font
					(size 1.27 1.27)
					(thickness 0.15)
				)
				(justify left bottom)
				(hide yes)
			)
		)
		(property "Footprint" "antmicro-footprints:C_0402_1005Metric"
			(at 242.57 144.145 0)
			(effects
				(font
					(size 1.27 1.27)
					(thickness 0.15)
				)
				(justify left bottom)
				(hide yes)
			)
		)
		(property "Datasheet" " "
			(at 240.03 144.145 0)
			(effects
				(font
					(size 1.27 1.27)
					(thickness 0.15)
				)
				(justify left bottom)
				(hide yes)
			)
		)
		(property "Description" ""
			(at 255.27 123.825 0)
			(effects
				(font
					(size 1.27 1.27)
				)
			)
		)
		(property "Manufacturer" "Walsin"
			(at 234.95 144.145 0)
			(effects
				(font
					(size 1.27 1.27)
					(thickness 0.15)
				)
				(justify left bottom)
				(hide yes)
			)
		)
		(property "MPN" "0402X104K6R3CT"
			(at 237.49 144.145 0)
			(effects
				(font
					(size 1.27 1.27)
					(thickness 0.15)
				)
				(justify left bottom)
				(hide yes)
			)
		)
		(property "Val" "100n"
			(at 255.905 129.54 90)
			(effects
				(font
					(size 1.27 1.27)
					(thickness 0.15)
				)
				(justify left bottom)
			)
		)
		(property "License" "Apache-2.0"
			(at 232.41 144.145 0)
			(effects
				(font
					(size 1.27 1.27)
					(thickness 0.15)
				)
				(justify left bottom)
				(hide yes)
			)
		)
		(property "Author" "Antmicro"
			(at 229.87 144.145 0)
			(effects
				(font
					(size 1.27 1.27)
					(thickness 0.15)
				)
				(justify left bottom)
				(hide yes)
			)
		)
		(property "Voltage" ""
			(at 227.33 144.145 0)
			(effects
				(font
					(size 1.27 1.27)
				)
				(justify left bottom)
				(hide yes)
			)
		)
		(property "Dielectric" ""
			(at 224.79 144.145 0)
			(effects
				(font
					(size 1.27 1.27)
				)
				(justify left bottom)
				(hide yes)
			)
		)
		(pin "1"
		)
		(pin "2"
		)
		(instances
			(project "lpddr4-test-board"
				(path ""
					(reference "C4")
					(unit 1)
				)
			)
		)
	)
	(symbol
		(lib_id "antmicropower:GND")
		(at 255.27 131.445 0)
		(unit 1)
		(exclude_from_sim no)
		(in_bom yes)
		(on_board yes)
		(dnp no)
		(property "Reference" "#PWR05"
			(at 264.16 133.985 0)
			(effects
				(font
					(size 1.27 1.27)
					(thickness 0.15)
				)
				(justify left bottom)
				(hide yes)
			)
		)
		(property "Value" "GND"
			(at 253.365 135.89 0)
			(effects
				(font
					(size 1.27 1.27)
					(thickness 0.15)
				)
				(justify left bottom)
			)
		)
		(property "Footprint" ""
			(at 264.16 139.065 0)
			(effects
				(font
					(size 1.27 1.27)
					(thickness 0.15)
				)
				(justify left bottom)
				(hide yes)
			)
		)
		(property "Datasheet" ""
			(at 264.16 144.145 0)
			(effects
				(font
					(size 1.27 1.27)
					(thickness 0.15)
				)
				(justify left bottom)
				(hide yes)
			)
		)
		(property "Description" ""
			(at 255.27 131.445 0)
			(effects
				(font
					(size 1.27 1.27)
				)
			)
		)
		(property "Author" "Antmicro"
			(at 264.16 139.065 0)
			(effects
				(font
					(size 1.27 1.27)
					(thickness 0.15)
				)
				(justify left bottom)
				(hide yes)
			)
		)
		(property "License" "Apache-2.0"
			(at 264.16 141.605 0)
			(effects
				(font
					(size 1.27 1.27)
					(thickness 0.15)
				)
				(justify left bottom)
				(hide yes)
			)
		)
		(pin "1"
		)
		(instances
			(project "lpddr4-test-board"
				(path ""
					(reference "#PWR05")
					(unit 1)
				)
			)
		)
	)
)
